# T6G (Grand Teton) — schematic netlist excerpt (pin names and nets, part order shuffled) for the footprints in the layout excerpt that follows; sources: Cadence DE-HDL packaged netlist, KiCad conversion of 04192023_DAF0TMB3IC0_F0TG_MB_C_brd_V02_OCP.brd

C303  Q_CAP  10PF 50V 5% EMPTY  pkg 0402  page 200 : A = SVID_PVDDCR_CPU1_P0_SVTO ; B = GND
L31  Q_INDUCTOR  BLM15PD121SN1D/1300MA IND  pkg SMLF  page 334 : \1\ = P1V8_CPU1_RT_1D ; \2\ = P1V8_CPU1_RT1_1A_1D

(kicad_pcb
	(version 20260206)
	(generator "pcbnew")
	(generator_version "10.0")
	(general
		(thickness 1.6)
		(legacy_teardrops no)
	)
	(paper "A4")
	(title_block
		(title "04192023_DAF0TMB3IC0_F0TG_MB_C_brd_V02_OCP.brd")
		(comment 1 "Grand Teton / footprints 1839-1840 of 8354")
	)
	(layers
		(0 "F.Cu" signal "TOP")
		(4 "In1.Cu" signal "GND")
		(6 "In2.Cu" signal "IN1")
		(8 "In3.Cu" signal "GND1")
		(10 "In4.Cu" signal "IN2")
		(12 "In5.Cu" signal "GND2")
		(14 "In6.Cu" signal "IN3")
		(16 "In7.Cu" signal "GND3")
		(18 "In8.Cu" signal "VCC")
		(20 "In9.Cu" signal "VCC1")
		(22 "In10.Cu" signal "GND4")
		(24 "In11.Cu" signal "IN4")
		(26 "In12.Cu" signal "GND5")
		(28 "In13.Cu" signal "IN5")
		(30 "In14.Cu" signal "GND6")
		(32 "In15.Cu" signal "IN6")
		(34 "In16.Cu" signal "GND7")
		(2 "B.Cu" signal "BOTTOM")
		(9 "F.Adhes" user "F.Adhesive")
		(11 "B.Adhes" user "B.Adhesive")
		(13 "F.Paste" user "Package Geometry/Pastemask Top")
		(15 "B.Paste" user "Package Geometry/Pastemask Bottom")
		(5 "F.SilkS" user "Ref Des/Silkscreen Top")
		(7 "B.SilkS" user "Ref Des/Silkscreen Bottom")
		(1 "F.Mask" user "Board Geometry/Soldermask Top")
		(3 "B.Mask" user "Board Geometry/Soldermask Bottom")
		(17 "Dwgs.User" user "User.Drawings")
		(19 "Cmts.User" user "User.Comments")
		(21 "Eco1.User" user "User.Eco1")
		(23 "Eco2.User" user "User.Eco2")
		(25 "Edge.Cuts" user "Board Geometry/Outline")
		(27 "Margin" user)
		(31 "F.CrtYd" user "Package Geometry/Place Bound Top")
		(29 "B.CrtYd" user "Package Geometry/Place Bound Bottom")
		(35 "F.Fab" user "Ref Des/Assembly Top")
		(33 "B.Fab" user "Ref Des/Assembly Bottom")
	)
	(footprint ""
		(layer "F.Cu")
		(at 302.133 -355.854 180)
		(property "Reference" "C303"
			(at 0 0 180)
			(layer "F.SilkS")
			(hide yes)
			(effects
				(font
					(size 1.27 1.27)
				)
			)
		)
		(property "Value" ""
			(at 0 0 180)
			(layer "F.Fab")
			(effects
				(font
					(size 1.27 1.27)
				)
			)
		)
		(duplicate_pad_numbers_are_jumpers no)
		(fp_line
			(start 0.7874 0.4064)
			(end -0.7874 0.4064)
			(stroke
				(width 0.1524)
				(type default)
			)
			(layer "F.SilkS")
		)
		(fp_line
			(start 0.7874 -0.4064)
			(end 0.7874 0.4064)
			(stroke
				(width 0.1524)
				(type default)
			)
			(layer "F.SilkS")
		)
		(fp_line
			(start -0.7874 0.4064)
			(end -0.7874 -0.4064)
			(stroke
				(width 0.1524)
				(type default)
			)
			(layer "F.SilkS")
		)
		(fp_line
			(start -0.7874 -0.4064)
			(end 0.7874 -0.4064)
			(stroke
				(width 0.1524)
				(type default)
			)
			(layer "F.SilkS")
		)
		(fp_line
			(start 0.67945 0.3048)
			(end 0.120396 0.3048)
			(stroke
				(width 0.1)
				(type default)
			)
			(layer "F.Fab")
		)
		(fp_line
			(start 0.67945 -0.3048)
			(end 0.67945 0.3048)
			(stroke
				(width 0.1)
				(type default)
			)
			(layer "F.Fab")
		)
		(fp_line
			(start 0.12065 -0.2794)
			(end 0.12065 -0.3048)
			(stroke
				(width 0.1)
				(type default)
			)
			(layer "F.Fab")
		)
		(fp_line
			(start 0.12065 -0.3048)
			(end 0.67945 -0.3048)
			(stroke
				(width 0.1)
				(type default)
			)
			(layer "F.Fab")
		)
		(fp_line
			(start 0.120396 0.3048)
			(end 0.120396 0.2794)
			(stroke
				(width 0.1)
				(type default)
			)
			(layer "F.Fab")
		)
		(fp_line
			(start 0.120396 0.2794)
			(end -0.12065 0.2794)
			(stroke
				(width 0.1)
				(type default)
			)
			(layer "F.Fab")
		)
		(fp_line
			(start -0.12065 0.3048)
			(end -0.67945 0.3048)
			(stroke
				(width 0.1)
				(type default)
			)
			(layer "F.Fab")
		)
		(fp_line
			(start -0.12065 0.2794)
			(end -0.12065 0.3048)
			(stroke
				(width 0.1)
				(type default)
			)
			(layer "F.Fab")
		)
		(fp_line
			(start -0.12065 -0.2794)
			(end 0.12065 -0.2794)
			(stroke
				(width 0.1)
				(type default)
			)
			(layer "F.Fab")
		)
		(fp_line
			(start -0.12065 -0.305054)
			(end -0.12065 -0.2794)
			(stroke
				(width 0.1)
				(type default)
			)
			(layer "F.Fab")
		)
		(fp_line
			(start -0.67945 0.3048)
			(end -0.67945 -0.305054)
			(stroke
				(width 0.1)
				(type default)
			)
			(layer "F.Fab")
		)
		(fp_line
			(start -0.67945 -0.305054)
			(end -0.12065 -0.305054)
			(stroke
				(width 0.1)
				(type default)
			)
			(layer "F.Fab")
		)
		(pad "1" smd circle
			(at -0.40005 0 180)
			(size 0 0)
			(layers "F.Cu" "F.Mask" "F.Paste")
			(net "SVID_PVDDCR_CPU1_P0_SVTO")
		)
		(pad "2" smd circle
			(at 0.40005 0 180)
			(size 0 0)
			(layers "F.Cu" "F.Mask" "F.Paste")
			(net "GND")
		)
	)
	(footprint ""
		(layer "F.Cu")
		(at 103.190294 -385.09448 180)
		(property "Reference" "L31"
			(at 0 0 180)
			(layer "F.SilkS")
			(hide yes)
			(effects
				(font
					(size 1.27 1.27)
				)
			)
		)
		(property "Value" ""
			(at 0 0 180)
			(layer "F.Fab")
			(effects
				(font
					(size 1.27 1.27)
				)
			)
		)
		(duplicate_pad_numbers_are_jumpers no)
		(fp_line
			(start 0.762 0.381)
			(end -0.762 0.381)
			(stroke
				(width 0.1524)
				(type default)
			)
			(layer "F.SilkS")
		)
		(fp_line
			(start 0.762 -0.381)
			(end 0.762 0.381)
			(stroke
				(width 0.1524)
				(type default)
			)
			(layer "F.SilkS")
		)
		(fp_line
			(start -0.762 0.381)
			(end -0.762 -0.381)
			(stroke
				(width 0.1524)
				(type default)
			)
			(layer "F.SilkS")
		)
		(fp_line
			(start -0.762 -0.381)
			(end 0.762 -0.381)
			(stroke
				(width 0.1524)
				(type default)
			)
			(layer "F.SilkS")
		)
		(fp_line
			(start 0.680466 0.306324)
			(end 0.118364 0.306324)
			(stroke
				(width 0.1)
				(type default)
			)
			(layer "F.Fab")
		)
		(fp_line
			(start 0.680466 -0.306324)
			(end 0.680466 0.306324)
			(stroke
				(width 0.1)
				(type default)
			)
			(layer "F.Fab")
		)
		(fp_line
			(start 0.118872 -0.2794)
			(end 0.118872 -0.306324)
			(stroke
				(width 0.1)
				(type default)
			)
			(layer "F.Fab")
		)
		(fp_line
			(start 0.118872 -0.306324)
			(end 0.680466 -0.306324)
			(stroke
				(width 0.1)
				(type default)
			)
			(layer "F.Fab")
		)
		(fp_line
			(start 0.118364 0.306324)
			(end 0.118364 0.2794)
			(stroke
				(width 0.1)
				(type default)
			)
			(layer "F.Fab")
		)
		(fp_line
			(start 0.118364 0.2794)
			(end -0.119634 0.2794)
			(stroke
				(width 0.1)
				(type default)
			)
			(layer "F.Fab")
		)
		(fp_line
			(start -0.118364 -0.2794)
			(end 0.118872 -0.2794)
			(stroke
				(width 0.1)
				(type default)
			)
			(layer "F.Fab")
		)
		(fp_line
			(start -0.118364 -0.307086)
			(end -0.118364 -0.2794)
			(stroke
				(width 0.1)
				(type default)
			)
			(layer "F.Fab")
		)
		(fp_line
			(start -0.119634 0.30607)
			(end -0.681736 0.30607)
			(stroke
				(width 0.1)
				(type default)
			)
			(layer "F.Fab")
		)
		(fp_line
			(start -0.119634 0.2794)
			(end -0.119634 0.30607)
			(stroke
				(width 0.1)
				(type default)
			)
			(layer "F.Fab")
		)
		(fp_line
			(start -0.681736 0.30607)
			(end -0.681736 -0.307086)
			(stroke
				(width 0.1)
				(type default)
			)
			(layer "F.Fab")
		)
		(fp_line
			(start -0.681736 -0.307086)
			(end -0.118364 -0.307086)
			(stroke
				(width 0.1)
				(type default)
			)
			(layer "F.Fab")
		)
		(pad "1" smd rect
			(at -0.40005 0)
			(size 0.4572 0.508)
			(layers "F.Cu" "F.Mask" "F.Paste")
			(net "P1V8_CPU1_RT_1D")
		)
		(pad "2" smd rect
			(at 0.40005 0)
			(size 0.4572 0.508)
			(layers "F.Cu" "F.Mask" "F.Paste")
			(net "P1V8_CPU1_RT1_1A_1D")
		)
	)
)
